#ISCELL
  mstr_misc dns *
  *
#ISCELL
  pure_quanta quanta_title_block_c *
  *
#CELL
  pure_quanta q_cap *
  page167_i15
#CELL
  pure_quanta mpq8633aglec807z *
  page167_i18
#CELL
  pure_quanta q_cap *
  page167_i19
#ISCELL
  pure_quanta_power universal_power *
  page167_i2
#CELL
  pure_quanta q_res *
  page167_i21
#CELL
  pure_quanta q_cap *
  page167_i22
#ISCELL
  pure_quanta_power universal_power *
  page167_i24
#CELL
  pure_quanta q_res *
  page167_i26
#CELL
  pure_quanta q_cap *
  page167_i27
#CELL
  pure_quanta q_res *
  page167_i29
#CELL
  pure_quanta q_cap *
  page167_i34
#CELL
  pure_quanta q_cap *
  page167_i35
#CELL
  pure_quanta q_cap *
  page167_i36
#CELL
  pure_quanta q_cap *
  page167_i37
#CELL
  pure_quanta q_cap *
  page167_i39
#ISCELL
  pure_quanta_power universal_power *
  page167_i40
#ISCELL
  pure_quanta_power universal_gnd *
  page167_i41
#ISCELL
  pure_quanta_power universal_gnd *
  page167_i44
#ISCELL
  pure_quanta_power universal_gnd *
  page167_i45
#ISCELL
  pure_quanta_power universal_gnd *
  page167_i46
#ISCELL
  pure_quanta_power universal_gnd *
  page167_i47
#ISCELL
  pure_quanta_power universal_gnd *
  page167_i48
#ISCELL
  pure_quanta_power universal_gnd *
  page167_i49
#CELL
  pure_quanta q_res *
  page167_i5
#CELL
  pure_quanta q_inductor *
  page167_i50
#ISCELL
  pure_quanta_power universal_gnd *
  page167_i51
#CELL
  pure_quanta q_cap *
  page167_i52
#ISCELL
  pure_quanta_power universal_power *
  page167_i53
#ISCELL
  standard offpage *
  page167_i54
#CELL
  pure_quanta q_inductor *
  page167_i56
#ISCELL
  pure_quanta_power universal_gnd *
  page167_i57
#CELL
  pure_quanta q_cap *
  page167_i58
#ISCELL
  standard offpage *
  page167_i59
#CELL
  pure_quanta q_res *
  page167_i60
#CELL
  pure_quanta q_cap *
  page167_i7
#CELL
  pure_quanta q_cap *
  page167_i8
#CELL
  pure_quanta q_cap *
  page167_i9
